(kicad_pcb
	(version 20260206)
	(generator "pcbnew")
	(generator_version "10.0")
	(general
		(thickness 1.6)
		(legacy_teardrops no)
	)
	(paper "A4")
	(title_block
		(title "peb — Lightning_PEB_BRD.brd")
		(comment 1 "Lightning (Wiwynn / Facebook NVMe JBOF) / footprints 2061-2068 of 2563")
	)
	(layers
		(0 "F.Cu" signal "TOP")
		(4 "In1.Cu" signal "L2GND")
		(6 "In2.Cu" signal "L3")
		(8 "In3.Cu" signal "L4VCC")
		(10 "In4.Cu" signal "L5VCC")
		(12 "In5.Cu" signal "L6")
		(14 "In6.Cu" signal "L7GND")
		(2 "B.Cu" signal "BOTTOM")
		(9 "F.Adhes" user "F.Adhesive")
		(11 "B.Adhes" user "B.Adhesive")
		(13 "F.Paste" user "Package Geometry/Pastemask Top")
		(15 "B.Paste" user "Package Geometry/Pastemask Bottom")
		(5 "F.SilkS" user "Ref Des/Silkscreen Top")
		(7 "B.SilkS" user "Ref Des/Silkscreen Bottom")
		(1 "F.Mask" user "Board Geometry/Soldermask Top")
		(3 "B.Mask" user "Board Geometry/Soldermask Bottom")
		(17 "Dwgs.User" user "User.Drawings")
		(19 "Cmts.User" user "User.Comments")
		(21 "Eco1.User" user "User.Eco1")
		(23 "Eco2.User" user "User.Eco2")
		(25 "Edge.Cuts" user "Board Geometry/Outline")
		(27 "Margin" user)
		(31 "F.CrtYd" user "Package Geometry/Place Bound Top")
		(29 "B.CrtYd" user "Package Geometry/Place Bound Bottom")
		(35 "F.Fab" user "Ref Des/Assembly Top")
		(33 "B.Fab" user "Ref Des/Assembly Bottom")
	)
	(footprint ""
		(layer "B.Cu")
		(at 74.950066 -195.6689 180)
		(property "Reference" "R4114"
			(at 0 0 0)
			(layer "B.SilkS")
			(hide yes)
			(effects
				(font
					(size 1.27 1.27)
				)
				(justify mirror)
			)
		)
		(property "Value" "4K7R2F-GP"
			(at -0.064008 -3.993896 180)
			(unlocked yes)
			(layer "B.Fab")
			(hide yes)
			(effects
				(font
					(size 1.016 1.016)
					(thickness 0.1524)
				)
				(justify mirror)
			)
		)
		(property "Device Type" "R402H16"
			(at -0.064008 -5.517896 180)
			(unlocked yes)
			(layer "B.Fab")
			(hide yes)
			(effects
				(font
					(size 1.016 1.016)
					(thickness 0.1524)
				)
				(justify mirror)
			)
		)
		(duplicate_pad_numbers_are_jumpers no)
		(fp_line
			(start 0.508 -0.9398)
			(end 0.508 0.9398)
			(stroke
				(width 0.1524)
				(type default)
			)
			(layer "B.SilkS")
		)
		(fp_line
			(start -0.508 -0.9398)
			(end 0.508 -0.9398)
			(stroke
				(width 0.1524)
				(type default)
			)
			(layer "B.SilkS")
		)
		(fp_rect
			(start 0.508 0.9398)
			(end -0.508 -0.9398)
			(stroke
				(width 0)
				(type default)
			)
			(fill no)
			(layer "B.CrtYd")
		)
		(fp_rect
			(start 0.508 0.9398)
			(end -0.508 -0.9398)
			(stroke
				(width 0)
				(type default)
			)
			(fill no)
			(layer "B.Fab")
		)
		(pad "1" smd custom
			(at 0 -0.4445)
			(size 0.1397 0.1397)
			(layers "B.Cu" "B.Mask" "B.Paste")
			(net "SSD_ATNLED#11")
			(options
				(clearance outline)
				(anchor circle)
			)
			(primitives
				(gr_poly
					(pts
						(arc
							(start -0.1778 0.2794)
							(mid -0.249642 0.249642)
							(end -0.2794 0.1778)
						)
						(arc
							(start -0.2794 -0.1778)
							(mid -0.249642 -0.249642)
							(end -0.1778 -0.2794)
						)
						(arc
							(start 0.1778 -0.2794)
							(mid 0.249642 -0.249642)
							(end 0.2794 -0.1778)
						)
						(arc
							(start 0.2794 0.1778)
							(mid 0.249642 0.249642)
							(end 0.1778 0.2794)
						)
					)
					(width 0)
					(fill yes)
				)
			)
		)
		(pad "2" smd custom
			(at 0 0.4445)
			(size 0.1397 0.1397)
			(layers "B.Cu" "B.Mask" "B.Paste")
			(net "P3V3_STBY")
			(options
				(clearance outline)
				(anchor circle)
			)
			(primitives
				(gr_poly
					(pts
						(arc
							(start -0.1778 0.2794)
							(mid -0.249642 0.249642)
							(end -0.2794 0.1778)
						)
						(arc
							(start -0.2794 -0.1778)
							(mid -0.249642 -0.249642)
							(end -0.1778 -0.2794)
						)
						(arc
							(start 0.1778 -0.2794)
							(mid 0.249642 -0.249642)
							(end 0.2794 -0.1778)
						)
						(arc
							(start 0.2794 0.1778)
							(mid 0.249642 0.249642)
							(end 0.1778 0.2794)
						)
					)
					(width 0)
					(fill yes)
				)
			)
		)
	)
	(footprint ""
		(layer "B.Cu")
		(at 221.107 -10.3124 180)
		(property "Reference" "U81"
			(at 0 0 0)
			(layer "B.SilkS")
			(hide yes)
			(effects
				(font
					(size 1.27 1.27)
				)
				(justify mirror)
			)
		)
		(property "Value" "SN74LVC1G08DCKR-GP"
			(at 2.3368 -8.6868 180)
			(unlocked yes)
			(layer "B.Fab")
			(hide yes)
			(effects
				(font
					(size 1.016 1.016)
					(thickness 0.1524)
				)
				(justify mirror)
			)
		)
		(property "Device Type" "SC70-5H44"
			(at 2.3114 -10.414 180)
			(unlocked yes)
			(layer "B.Fab")
			(hide yes)
			(effects
				(font
					(size 1.016 1.016)
					(thickness 0.1524)
				)
				(justify mirror)
			)
		)
		(duplicate_pad_numbers_are_jumpers no)
		(fp_line
			(start 1.27 1.7018)
			(end 1.27 -1.7018)
			(stroke
				(width 0.1524)
				(type default)
			)
			(layer "B.SilkS")
		)
		(fp_line
			(start 1.27 -1.7018)
			(end -1.27 -1.7018)
			(stroke
				(width 0.1524)
				(type default)
			)
			(layer "B.SilkS")
		)
		(fp_line
			(start -0.6604 -1.8034)
			(end -1.3843 -1.8034)
			(stroke
				(width 0.3302)
				(type default)
			)
			(layer "B.SilkS")
		)
		(fp_line
			(start -1.27 1.7018)
			(end 1.27 1.7018)
			(stroke
				(width 0.1524)
				(type default)
			)
			(layer "B.SilkS")
		)
		(fp_line
			(start -1.27 -1.7018)
			(end -1.27 1.7018)
			(stroke
				(width 0.1524)
				(type default)
			)
			(layer "B.SilkS")
		)
		(fp_line
			(start -1.3843 -1.8034)
			(end -1.3843 -1.1176)
			(stroke
				(width 0.3302)
				(type default)
			)
			(layer "B.SilkS")
		)
		(fp_rect
			(start 1.524 1.9558)
			(end -1.524 -1.9558)
			(stroke
				(width 0)
				(type default)
			)
			(fill no)
			(layer "B.CrtYd")
		)
		(fp_poly
			(pts
				(xy 1.524 -1.9558) (xy -1.524 -1.9558) (xy -1.524 1.9558) (xy 1.524 1.9558)
			)
			(stroke
				(width 0)
				(type default)
			)
			(fill no)
			(layer "B.Fab")
		)
		(pad "1" smd rect
			(at -0.65024 -0.8255)
			(size 0.4064 1.2192)
			(layers "B.Cu" "B.Mask" "B.Paste")
			(net "HOST1_RST_N")
		)
		(pad "2" smd rect
			(at 0 -0.8255)
			(size 0.4064 1.2192)
			(layers "B.Cu" "B.Mask" "B.Paste")
			(net "U81_B")
		)
		(pad "3" smd rect
			(at 0.65024 -0.8255)
			(size 0.4064 1.2192)
			(layers "B.Cu" "B.Mask" "B.Paste")
			(net "GND")
		)
		(pad "4" smd rect
			(at 0.65024 0.8255)
			(size 0.4064 1.2192)
			(layers "B.Cu" "B.Mask" "B.Paste")
			(net "U81_Y")
		)
		(pad "5" smd rect
			(at -0.65024 0.8255)
			(size 0.4064 1.2192)
			(layers "B.Cu" "B.Mask" "B.Paste")
			(net "P3V3_STBY")
		)
	)
	(footprint ""
		(layer "B.Cu")
		(at 241.0968 -43.997372 -90)
		(property "Reference" "C428"
			(at 0 0 90)
			(layer "B.SilkS")
			(hide yes)
			(effects
				(font
					(size 1.27 1.27)
				)
				(justify mirror)
			)
		)
		(property "Value" "SCD1U16V1KX-1-GP"
			(at 2.8321 -1.7399 270)
			(unlocked yes)
			(layer "B.Fab")
			(hide yes)
			(effects
				(font
					(size 1.016 1.016)
					(thickness 0.1524)
				)
				(justify mirror)
			)
		)
		(property "Device Type" "C0201H13"
			(at 2.8321 -3.2639 270)
			(unlocked yes)
			(layer "B.Fab")
			(hide yes)
			(effects
				(font
					(size 1.016 1.016)
					(thickness 0.1524)
				)
				(justify mirror)
			)
		)
		(duplicate_pad_numbers_are_jumpers no)
		(fp_rect
			(start 0.2794 0.6477)
			(end -0.2794 -0.6477)
			(stroke
				(width 0)
				(type default)
			)
			(fill no)
			(layer "B.CrtYd")
		)
		(fp_rect
			(start 0.2794 0.6477)
			(end -0.2794 -0.6477)
			(stroke
				(width 0)
				(type default)
			)
			(fill no)
			(layer "B.Fab")
		)
		(pad "1" smd custom
			(at 0 -0.2794 90)
			(size 0.0762 0.0762)
			(layers "B.Cu" "B.Mask" "B.Paste")
			(net "DUT_VDD")
			(options
				(clearance outline)
				(anchor circle)
			)
			(primitives
				(gr_poly
					(pts
						(arc
							(start 0.1524 0.127)
							(mid 0.137521 0.162921)
							(end 0.1016 0.1778)
						)
						(arc
							(start -0.1016 0.1778)
							(mid -0.137521 0.162921)
							(end -0.1524 0.127)
						)
						(arc
							(start -0.1524 -0.127)
							(mid -0.137521 -0.162921)
							(end -0.1016 -0.1778)
						)
						(arc
							(start 0.1016 -0.1778)
							(mid 0.137521 -0.162921)
							(end 0.1524 -0.127)
						)
					)
					(width 0)
					(fill yes)
				)
			)
		)
		(pad "2" smd custom
			(at 0 0.2794 90)
			(size 0.0762 0.0762)
			(layers "B.Cu" "B.Mask" "B.Paste")
			(net "GND")
			(options
				(clearance outline)
				(anchor circle)
			)
			(primitives
				(gr_poly
					(pts
						(arc
							(start 0.1524 0.127)
							(mid 0.137521 0.162921)
							(end 0.1016 0.1778)
						)
						(arc
							(start -0.1016 0.1778)
							(mid -0.137521 0.162921)
							(end -0.1524 0.127)
						)
						(arc
							(start -0.1524 -0.127)
							(mid -0.137521 -0.162921)
							(end -0.1016 -0.1778)
						)
						(arc
							(start 0.1016 -0.1778)
							(mid 0.137521 -0.162921)
							(end 0.1524 -0.127)
						)
					)
					(width 0)
					(fill yes)
				)
			)
		)
	)
	(footprint ""
		(layer "B.Cu")
		(at 310.007 -58.547 180)
		(property "Reference" "PG40"
			(at 0 0 0)
			(layer "B.SilkS")
			(hide yes)
			(effects
				(font
					(size 1.27 1.27)
				)
				(justify mirror)
			)
		)
		(property "Value" "GAP-CLOSE-PWR-3-GP"
			(at -0.0254 -6.5786 180)
			(unlocked yes)
			(layer "B.Fab")
			(hide yes)
			(effects
				(font
					(size 1.016 1.016)
					(thickness 0.1524)
				)
				(justify mirror)
			)
		)
		(property "Device Type" "GAP-CLOSE-PWR-3"
			(at -0.0254 -8.255 180)
			(unlocked yes)
			(layer "B.Fab")
			(hide yes)
			(effects
				(font
					(size 1.016 1.016)
					(thickness 0.1524)
				)
				(justify mirror)
			)
		)
		(duplicate_pad_numbers_are_jumpers no)
		(fp_rect
			(start 0.7112 0.4572)
			(end -0.7112 -0.4572)
			(stroke
				(width 0)
				(type default)
			)
			(fill no)
			(layer "B.CrtYd")
		)
		(fp_poly
			(pts
				(xy 0.7112 -0.4572) (xy -0.7112 -0.4572) (xy -0.7112 0.4572) (xy 0.7112 0.4572)
			)
			(stroke
				(width 0)
				(type default)
			)
			(fill no)
			(layer "B.Fab")
		)
		(pad "1" smd rect
			(at 0.3048 0)
			(size 0.6604 0.762)
			(layers "B.Cu" "B.Mask" "B.Paste")
			(net "DUT_VDD")
		)
		(pad "2" smd rect
			(at -0.3048 0)
			(size 0.6604 0.762)
			(layers "B.Cu" "B.Mask" "B.Paste")
			(net "P0V9_E")
		)
	)
	(footprint ""
		(layer "B.Cu")
		(at 34.613088 -126.105412)
		(property "Reference" "TP245"
			(at 0 0 0)
			(layer "B.SilkS")
			(hide yes)
			(effects
				(font
					(size 1.27 1.27)
				)
				(justify mirror)
			)
		)
		(property "Value" "TPAD28-2-GP"
			(at 0.0127 -1.6637 0)
			(unlocked yes)
			(layer "B.Fab")
			(hide yes)
			(effects
				(font
					(size 1.016 1.016)
					(thickness 0.1524)
				)
				(justify mirror)
			)
		)
		(property "Device Type" "TPAD28"
			(at 0.0127 -3.1877 0)
			(unlocked yes)
			(layer "B.Fab")
			(hide yes)
			(effects
				(font
					(size 1.016 1.016)
					(thickness 0.1524)
				)
				(justify mirror)
			)
		)
		(duplicate_pad_numbers_are_jumpers no)
		(fp_poly
			(pts
				(arc
					(start 0.3556 0)
					(mid -0.3556 0)
					(end 0.3556 0)
				)
			)
			(stroke
				(width 0)
				(type default)
			)
			(fill no)
			(layer "B.CrtYd")
		)
		(fp_poly
			(pts
				(arc
					(start 0.6096 0)
					(mid -0.6096 0)
					(end 0.6096 0)
				)
			)
			(stroke
				(width 0)
				(type default)
			)
			(fill no)
			(layer "B.Fab")
		)
		(pad "1" smd circle
			(at 0 0 180)
			(size 0.7112 0.7112)
			(layers "B.Cu" "B.Mask" "B.Paste")
			(net "TP_GPIOB5")
		)
	)
	(footprint ""
		(layer "B.Cu")
		(at 23.941786 -131.462018 90)
		(property "Reference" "R355"
			(at 0 0 90)
			(layer "B.SilkS")
			(hide yes)
			(effects
				(font
					(size 1.27 1.27)
				)
				(justify mirror)
			)
		)
		(property "Value" "3K3R2F-2-GP"
			(at -0.064008 -3.993896 90)
			(unlocked yes)
			(layer "B.Fab")
			(hide yes)
			(effects
				(font
					(size 1.016 1.016)
					(thickness 0.1524)
				)
				(justify mirror)
			)
		)
		(property "Device Type" "R402H16"
			(at -0.064008 -5.517896 90)
			(unlocked yes)
			(layer "B.Fab")
			(hide yes)
			(effects
				(font
					(size 1.016 1.016)
					(thickness 0.1524)
				)
				(justify mirror)
			)
		)
		(duplicate_pad_numbers_are_jumpers no)
		(fp_line
			(start 0.508 -0.9398)
			(end 0.508 0.9398)
			(stroke
				(width 0.1524)
				(type default)
			)
			(layer "B.SilkS")
		)
		(fp_line
			(start -0.508 -0.9398)
			(end 0.508 -0.9398)
			(stroke
				(width 0.1524)
				(type default)
			)
			(layer "B.SilkS")
		)
		(fp_rect
			(start 0.508 0.9398)
			(end -0.508 -0.9398)
			(stroke
				(width 0)
				(type default)
			)
			(fill no)
			(layer "B.CrtYd")
		)
		(fp_rect
			(start 0.508 0.9398)
			(end -0.508 -0.9398)
			(stroke
				(width 0)
				(type default)
			)
			(fill no)
			(layer "B.Fab")
		)
		(pad "1" smd custom
			(at 0 -0.4445 270)
			(size 0.1397 0.1397)
			(layers "B.Cu" "B.Mask" "B.Paste")
			(net "P3V3_STBY")
			(options
				(clearance outline)
				(anchor circle)
			)
			(primitives
				(gr_poly
					(pts
						(arc
							(start -0.1778 0.2794)
							(mid -0.249642 0.249642)
							(end -0.2794 0.1778)
						)
						(arc
							(start -0.2794 -0.1778)
							(mid -0.249642 -0.249642)
							(end -0.1778 -0.2794)
						)
						(arc
							(start 0.1778 -0.2794)
							(mid 0.249642 -0.249642)
							(end 0.2794 -0.1778)
						)
						(arc
							(start 0.2794 0.1778)
							(mid 0.249642 0.249642)
							(end 0.1778 0.2794)
						)
					)
					(width 0)
					(fill yes)
				)
			)
		)
		(pad "2" smd custom
			(at 0 0.4445 270)
			(size 0.1397 0.1397)
			(layers "B.Cu" "B.Mask" "B.Paste")
			(net "ROMA4")
			(options
				(clearance outline)
				(anchor circle)
			)
			(primitives
				(gr_poly
					(pts
						(arc
							(start -0.1778 0.2794)
							(mid -0.249642 0.249642)
							(end -0.2794 0.1778)
						)
						(arc
							(start -0.2794 -0.1778)
							(mid -0.249642 -0.249642)
							(end -0.1778 -0.2794)
						)
						(arc
							(start 0.1778 -0.2794)
							(mid 0.249642 -0.249642)
							(end 0.2794 -0.1778)
						)
						(arc
							(start 0.2794 0.1778)
							(mid 0.249642 0.249642)
							(end 0.1778 0.2794)
						)
					)
					(width 0)
					(fill yes)
				)
			)
		)
	)
	(footprint ""
		(layer "B.Cu")
		(at 53.7845 -124.902976 -90)
		(property "Reference" "R799"
			(at 0 0 90)
			(layer "B.SilkS")
			(hide yes)
			(effects
				(font
					(size 1.27 1.27)
				)
				(justify mirror)
			)
		)
		(property "Value" "4K7R2F-GP"
			(at -0.064008 -3.993896 270)
			(unlocked yes)
			(layer "B.Fab")
			(hide yes)
			(effects
				(font
					(size 1.016 1.016)
					(thickness 0.1524)
				)
				(justify mirror)
			)
		)
		(property "Device Type" "R402H16"
			(at -0.064008 -5.517896 270)
			(unlocked yes)
			(layer "B.Fab")
			(hide yes)
			(effects
				(font
					(size 1.016 1.016)
					(thickness 0.1524)
				)
				(justify mirror)
			)
		)
		(duplicate_pad_numbers_are_jumpers no)
		(fp_line
			(start -0.508 -0.9398)
			(end 0.508 -0.9398)
			(stroke
				(width 0.1524)
				(type default)
			)
			(layer "B.SilkS")
		)
		(fp_line
			(start 0.508 -0.9398)
			(end 0.508 0.9398)
			(stroke
				(width 0.1524)
				(type default)
			)
			(layer "B.SilkS")
		)
		(fp_rect
			(start 0.508 0.9398)
			(end -0.508 -0.9398)
			(stroke
				(width 0)
				(type default)
			)
			(fill no)
			(layer "B.CrtYd")
		)
		(fp_rect
			(start 0.508 0.9398)
			(end -0.508 -0.9398)
			(stroke
				(width 0)
				(type default)
			)
			(fill no)
			(layer "B.Fab")
		)
		(pad "1" smd custom
			(at 0 -0.4445 90)
			(size 0.1397 0.1397)
			(layers "B.Cu" "B.Mask" "B.Paste")
			(net "P3V3_STBY")
			(options
				(clearance outline)
				(anchor circle)
			)
			(primitives
				(gr_poly
					(pts
						(arc
							(start -0.1778 0.2794)
							(mid -0.249642 0.249642)
							(end -0.2794 0.1778)
						)
						(arc
							(start -0.2794 -0.1778)
							(mid -0.249642 -0.249642)
							(end -0.1778 -0.2794)
						)
						(arc
							(start 0.1778 -0.2794)
							(mid 0.249642 -0.249642)
							(end 0.2794 -0.1778)
						)
						(arc
							(start 0.2794 0.1778)
							(mid 0.249642 0.249642)
							(end 0.1778 0.2794)
						)
					)
					(width 0)
					(fill yes)
				)
			)
		)
		(pad "2" smd custom
			(at 0 0.4445 90)
			(size 0.1397 0.1397)
			(layers "B.Cu" "B.Mask" "B.Paste")
			(net "JTAG_BMC_TDO")
			(options
				(clearance outline)
				(anchor circle)
			)
			(primitives
				(gr_poly
					(pts
						(arc
							(start -0.1778 0.2794)
							(mid -0.249642 0.249642)
							(end -0.2794 0.1778)
						)
						(arc
							(start -0.2794 -0.1778)
							(mid -0.249642 -0.249642)
							(end -0.1778 -0.2794)
						)
						(arc
							(start 0.1778 -0.2794)
							(mid 0.249642 -0.249642)
							(end 0.2794 -0.1778)
						)
						(arc
							(start 0.2794 0.1778)
							(mid 0.249642 0.249642)
							(end 0.1778 0.2794)
						)
					)
					(width 0)
					(fill yes)
				)
			)
		)
	)
	(footprint ""
		(layer "B.Cu")
		(at 252.603 -47.997872 -90)
		(property "Reference" "C610"
			(at 0 0 90)
			(layer "B.SilkS")
			(hide yes)
			(effects
				(font
					(size 1.27 1.27)
				)
				(justify mirror)
			)
		)
		(property "Value" "SCD1U16V1KX-1-GP"
			(at 2.8321 -1.7399 270)
			(unlocked yes)
			(layer "B.Fab")
			(hide yes)
			(effects
				(font
					(size 1.016 1.016)
					(thickness 0.1524)
				)
				(justify mirror)
			)
		)
		(property "Device Type" "C0201H13"
			(at 2.8321 -3.2639 270)
			(unlocked yes)
			(layer "B.Fab")
			(hide yes)
			(effects
				(font
					(size 1.016 1.016)
					(thickness 0.1524)
				)
				(justify mirror)
			)
		)
		(duplicate_pad_numbers_are_jumpers no)
		(fp_rect
			(start 0.2794 0.6477)
			(end -0.2794 -0.6477)
			(stroke
				(width 0)
				(type default)
			)
			(fill no)
			(layer "B.CrtYd")
		)
		(fp_rect
			(start 0.2794 0.6477)
			(end -0.2794 -0.6477)
			(stroke
				(width 0)
				(type default)
			)
			(fill no)
			(layer "B.Fab")
		)
		(pad "1" smd custom
			(at 0 -0.2794 90)
			(size 0.0762 0.0762)
			(layers "B.Cu" "B.Mask" "B.Paste")
			(net "DUT_AVD_PCIE")
			(options
				(clearance outline)
				(anchor circle)
			)
			(primitives
				(gr_poly
					(pts
						(arc
							(start 0.1524 0.127)
							(mid 0.137521 0.162921)
							(end 0.1016 0.1778)
						)
						(arc
							(start -0.1016 0.1778)
							(mid -0.137521 0.162921)
							(end -0.1524 0.127)
						)
						(arc
							(start -0.1524 -0.127)
							(mid -0.137521 -0.162921)
							(end -0.1016 -0.1778)
						)
						(arc
							(start 0.1016 -0.1778)
							(mid 0.137521 -0.162921)
							(end 0.1524 -0.127)
						)
					)
					(width 0)
					(fill yes)
				)
			)
		)
		(pad "2" smd custom
			(at 0 0.2794 90)
			(size 0.0762 0.0762)
			(layers "B.Cu" "B.Mask" "B.Paste")
			(net "GND")
			(options
				(clearance outline)
				(anchor circle)
			)
			(primitives
				(gr_poly
					(pts
						(arc
							(start 0.1524 0.127)
							(mid 0.137521 0.162921)
							(end 0.1016 0.1778)
						)
						(arc
							(start -0.1016 0.1778)
							(mid -0.137521 0.162921)
							(end -0.1524 0.127)
						)
						(arc
							(start -0.1524 -0.127)
							(mid -0.137521 -0.162921)
							(end -0.1016 -0.1778)
						)
						(arc
							(start 0.1016 -0.1778)
							(mid 0.137521 -0.162921)
							(end 0.1524 -0.127)
						)
					)
					(width 0)
					(fill yes)
				)
			)
		)
	)
)
